FILE_TYPE = CONNECTIVITY;
{Allegro Design Entry HDL 17.2-2016 S081 (4005846) 1/11/2022}
"PAGE_NUMBER" = 268;
0"NC";
1"P3V3_AUX\g";
2"P3V3_AUX\g";
3"SW_P12V_PVCCINFAON_CPU0_FLT\g";
4"P3V3_AUX\g";
5"PVNN_MAIN_CPU0\g";
6"PVNN_MAIN_CPU0\g";
7"GND\g";
8"GND\g";
9"GND\g";
10"GND\g";
11"GND\g";
12"GND\g";
13"GND\g";
14"GND\g";
15"GND\g";
16"GND\g";
17"PVNN_MAIN_CPU0_FB";
18"SW_PVNN_MAIN_CPU0_SW";
19"PVNN_MAIN_CPU0_FB_RC";
20"PWRGD_PVNN_MAIN_CPU0";
21"SW_PVNN_MAIN_CPU0_BST_R";
22"SW_PVNN_MAIN_CPU0_BST";
23"PWRGD_PVNN_MAIN_CPU0_R";
24"PVNN_MAIN_CPU0_REF";
25"PVNN_MAIN_CPU0_VCC";
26"PVNN_MAIN_CPU0_CS";
27"FM_PVNN_MAIN_CPU0_EN";
28"PVNN_MAIN_CPU0_MODE";
%"UNIVERSAL_GND"
"1","(-8225,8375)","0","logical_power","I1";
;
CDS_LIB"logical_power"
HDL_POWER"GND";
"A"7;
%"Q_RES"
"2","(-8225,9350)","0","pure_quanta","I10";
;
PART_NUMBER"CS00002JB13"
PACK_TYPE"0402LF"
TOLERANCE"5%"
VALUE"0"
MATERIAL"CHIP"
WATTAGE"1/16W"
LOCATION"PR3339"
CDS_LIB"pure_quanta"
$SEC"1"
CDS_SEC"1";
"A"
$PN"1"2;
"B"
$PN"2"25;
%"Q_RES"
"2","(-9125,9675)","0","pure_quanta","I11";
;
PART_NUMBER"CS22002FB07"
PACK_TYPE"0402LF"
MATERIAL"CHIP"
WATTAGE"1/16W"
TOLERANCE"1%"
VALUE"2K"
LOCATION"R1445"
CDS_LIB"pure_quanta"
$SEC"1"
CDS_SEC"1";
"A"
$PN"1"27;
"B"
$PN"2"8;
%"UNIVERSAL_GND"
"1","(-8800,10225)","0","logical_power","I12";
;
CDS_LIB"logical_power"
HDL_POWER"GND";
"A"10;
%"Q_CAP"
"1","(-8800,10575)","0","pure_quanta","I13";
;
PART_NUMBER"CH6223MEA01"
TOLERANCE"20%"
MATERIAL"X6S"
VALUE"22UF"
VOLTAGE"16V"
PACK_TYPE"C0805"
LOCATION"PC1272"
CDS_LIB"pure_quanta"
BOM_COST"VR_PCH"
$SEC"1"
CDS_SEC"1";
"B"
$PN"2"10;
"A"
$PN"1"3;
%"VCCAUX15"
"1","(-8225,9550)","0","logical_power","I14";
;
HDL_POWER"P3V3_AUX"
BOM_COST"VR_PCH"
CDS_LIB"logical_power";
"A"2;
%"Q_CAP"
"1","(-8350,10575)","0","pure_quanta","I15";
;
PART_NUMBER"CH6223MEA01"
MATERIAL"X6S"
VOLTAGE"16V"
VALUE"22UF"
TOLERANCE"20%"
PACK_TYPE"C0805"
LOCATION"PC1273"
CDS_LIB"pure_quanta"
BOM_COST"VR_PCH"
$SEC"1"
CDS_SEC"1";
"B"
$PN"2"10;
"A"
$PN"1"3;
%"VCCAUX15"
"1","(-9125,11100)","0","logical_power","I16";
;
HDL_POWER"SW_P12V_PVCCINFAON_CPU0_FLT"
CDS_LIB"logical_power"
BOM_COST"VR_PCH";
"A"3;
%"UNIVERSAL_GND"
"1","(-7825,8375)","0","logical_power","I17";
;
CDS_LIB"logical_power"
HDL_POWER"GND";
"A"11;
%"UNIVERSAL_GND"
"1","(-6450,8250)","0","logical_power","I18";
;
CDS_LIB"logical_power"
HDL_POWER"GND";
"A"12;
%"Q_RES"
"1","(-5275,8375)","0","pure_quanta","I19";
;
PART_NUMBER"CS00002JB13"
TOLERANCE"5%"
VALUE"0"
MATERIAL"CHIP"
PACK_TYPE"0402LF"
WATTAGE"1/16W"
LOCATION"PR1"
CDS_LIB"pure_quanta"
$SEC"1"
CDS_SEC"1";
"B"
$PN"2"13;
"A"
$PN"1"12;
%"UNIVERSAL_GND"
"1","(-1550,8025)","0","logical_power","I20";
;
HDL_POWER"GND"
CDS_LIB"logical_power";
"A"13;
%"Q_RES"
"2","(-7825,8675)","0","pure_quanta","I21";
;
PART_NUMBER"CS32262FB02"
PACK_TYPE"0402LF"
MATERIAL"CHIP"
WATTAGE"1/16W"
TOLERANCE"1%"
VALUE"22.6K"
LOCATION"PR1303"
CDS_LIB"pure_quanta"
$SEC"1"
CDS_SEC"1";
"A"
$PN"1"26;
"B"
$PN"2"11;
%"RS53317LR"
"1","(-6900,9675)","0","pure_quanta","I22";
;
PART_NUMBER"AL053317005"
VALUE"RS53317LR"
PART_TYPE"SMLF"
MATERIAL"IC"
LOCATION"PU81"
SEC_TYPE""
CDS_LIB"pure_quanta"
NEEDS_NO_SIZE"TRUE"
CDS_LMAN_SYM_OUTLINE"-250,725,250,-725"
SEC"1";
"SW1"
$PN"2"18;
"CS"
$PN"4"26;
"MODE"
$PN"12"28;
"REF"
$PN"8"24;
"SW2"
$PN"11"18;
"PGND1"
$PN"1"14;
"VCC"
$PN"13"25;
"AGND"
$PN"7"12;
"FB"
$PN"6"17;
"BST"
$PN"10"22;
"EN"
$PN"5"27;
"PGND2"
$PN"14"14;
"PGOOD"
$PN"9"23;
"VIN"
$PN"3"3;
%"Q_CAP"
"1","(-7800,10575)","0","pure_quanta","I23";
;
PART_NUMBER"CH5103KEB01"
MATERIAL"X6S"
VALUE"1UF"
VOLTAGE"16V"
TOLERANCE"10%"
PACK_TYPE"C0402"
LOCATION"PC1274"
CDS_LIB"pure_quanta"
LOCATION"PC1274"
$SEC"1"
CDS_SEC"1";
"B"
$PN"2"10;
"A"
$PN"1"3;
%"UNIVERSAL_GND"
"1","(-6300,8750)","0","logical_power","I24";
;
CDS_LIB"logical_power"
HDL_POWER"GND";
"A"14;
%"Q_CAP"
"1","(-5825,8675)","0","pure_quanta","I25";
;
PART_NUMBER"TMP_QCH2336K1B12"
TOLERANCE"10%"
MATERIAL"X7R"
VALUE"3300PF"
VOLTAGE"50V"
PACK_TYPE"0402"
LOCATION"PC27"
CDS_LIB"pure_quanta"
$SEC"1"
CDS_SEC"1";
"B"
$PN"2"12;
"A"
$PN"1"24;
%"Q_CAP"
"1","(-5175,10000)","0","pure_quanta","I26";
;
PART_NUMBER"CH4224K1B01"
VALUE"0.22UF"
PACK_TYPE"C0402"
VOLTAGE"25V"
TOLERANCE"10%"
MATERIAL"X7R"
LOCATION"PC1275"
CDS_LIB"pure_quanta"
$SEC"1"
CDS_SEC"1";
"B"
$PN"2"18;
"A"
$PN"1"21;
%"Q_RES"
"1","(-5450,10150)","0","pure_quanta","I27";
;
PART_NUMBER"CS00002JB13"
PACK_TYPE"0402LF"
MATERIAL"CHIP"
VALUE"0"
TOLERANCE"5%"
LOCATION"PR4271"
CDS_LIB"pure_quanta"
SEC_TYPE"0402LF"
WATTAGE"1/16W"
SEC"1";
"B"
$PN"2"21;
"A"
$PN"1"22;
%"Q_RES"
"2","(-4600,8675)","0","pure_quanta","I28";
;
PART_NUMBER"CS31242BB10"
PACK_TYPE"0402LF"
VALUE"12.4K"
TOLERANCE"0.1%"
MATERIAL"CHIP"
WATTAGE"1/16W"
LOCATION"PR50"
CDS_LIB"pure_quanta"
SEC_TYPE"0402LF"
SEC"1";
"A"
$PN"1"17;
"B"
$PN"2"13;
%"Q_INDUCTOR"
"1","(-4475,9875)","0","pure_quanta","I29";
;
PART_NUMBER"CV-4755MZ12"
VALUE"4.7UH"
PACK_TYPE"SMLF"
MATERIAL"IND"
LOCATION"PL120"
BOM_COST"VR_PCH"
CDS_LIB"pure_quanta"
NEEDS_NO_SIZE"TRUE"
$SEC"1"
CDS_SEC"1";
"1"
$PN"1"18;
"2"
$PN"2"6;
%"VCCAUX15"
"1","(-10350,10175)","0","logical_power","I3";
;
HDL_POWER"P3V3_AUX"
BOM_COST"VR_PCH"
CDS_LIB"logical_power";
"A"1;
%"UNIVERSAL_GND"
"1","(-4350,10225)","0","logical_power","I30";
;
CDS_LIB"logical_power"
HDL_POWER"GND";
"A"15;
%"Q_CAP"
"1","(-4350,10450)","0","pure_quanta","I31";
;
PART_NUMBER"TMP_QCH21006JB10"
TOLERANCE"5%"
VOLTAGE"50V"
MATERIAL"X7R"
VALUE"1000PF"
PACK_TYPE"0402"
LOCATION"C1296"
CDS_LIB"pure_quanta"
$SEC"1"
CDS_SEC"1";
"B"
$PN"2"15;
"A"
$PN"1"20;
%"Q_RES"
"2","(-5425,10900)","0","pure_quanta","I32";
;
PART_NUMBER"CS31002FB08"
WATTAGE"1/16W"
TOLERANCE"1%"
MATERIAL"CHIP"
PACK_TYPE"0402LF"
VALUE"10K"
LOCATION"R2409"
BOM_COST"VR_PCH"
CDS_LIB"pure_quanta"
$SEC"1"
CDS_SEC"1";
"A"
$PN"1"4;
"B"
$PN"2"23;
%"Q_RES"
"1","(-5075,10625)","0","pure_quanta","I33";
;
PART_NUMBER"CS00002JB13"
TOLERANCE"5%"
MATERIAL"CHIP"
VALUE"0"
LOCATION"R1652"
CDS_LIB"pure_quanta"
PACK_TYPE"0402LF"
WATTAGE"1/16W"
$SEC"1"
CDS_SEC"1";
"B"
$PN"2"20;
"A"
$PN"1"23;
%"VCCAUX15"
"1","(-5425,11150)","0","logical_power","I34";
;
HDL_POWER"P3V3_AUX"
CDS_LIB"logical_power"
BOM_COST"VR_PCH";
"A"4;
%"Q_CAP"
"2","(-3425,8650)","0","pure_quanta","I35";
;
PART_NUMBER"TMP_QCH16806KB17"
VALUE"680PF"
VOLTAGE"50V"
PACK_TYPE"0402"
MATERIAL"X7R"
TOLERANCE"10%"
LOCATION"PC237"
CDS_LIB"pure_quanta"
$SEC"1"
CDS_SEC"1";
"A"
$PN"1"17;
"B"
$PN"2"19;
%"Q_RES"
"1","(-3425,9000)","0","pure_quanta","I36";
;
PART_NUMBER"CS28252BB01"
PACK_TYPE"0402LF"
MATERIAL"CHIP"
WATTAGE"1/16W"
VALUE"8.25K"
TOLERANCE"0.1%"
LOCATION"PR501"
CDS_LIB"pure_quanta"
$SEC"1"
CDS_SEC"1";
"B"
$PN"2"19;
"A"
$PN"1"17;
%"Q_CAP"
"1","(-3425,9650)","0","pure_quanta","I37";
;
PART_NUMBER"CH4106K1B01"
TOLERANCE"10%"
VALUE"100NF"
MATERIAL"X7R"
PACK_TYPE"C0402"
VOLTAGE"50V"
LOCATION"PC1276"
CDS_LIB"pure_quanta"
$SEC"1"
CDS_SEC"1";
"B"
$PN"2"16;
"A"
$PN"1"6;
%"Q_CAP"
"1","(-3050,9650)","0","pure_quanta","I38";
;
PART_NUMBER"CH622KMEA03"
PACK_TYPE"C0805"
TOLERANCE"20%"
VOLTAGE"4V"
VALUE"22UF"
MATERIAL"X6S"
LOCATION"PC1277"
BOM_COST"VR_PCH"
CDS_LIB"pure_quanta"
$SEC"1"
CDS_SEC"1";
"B"
$PN"2"16;
"A"
$PN"1"6;
%"Q_CAP"
"1","(-2725,8700)","0","pure_quanta","I39";
;
PART_NUMBER"TMP_QCH31004KB17"
TOLERANCE"10%"
MATERIAL"X7R"
VALUE"0.01UF"
PACK_TYPE"0402"
VOLTAGE"25V"
LOCATION"PC1420"
CDS_LIB"pure_quanta"
$SEC"1"
CDS_SEC"1";
"B"
$PN"2"13;
"A"
$PN"1"19;
%"Q_CAP"
"1","(-9225,9675)","2","pure_quanta","I4";
;
PART_NUMBER"TMP_QCH21006JB10"
VALUE"1000PF"
PACK_TYPE"0402"
VOLTAGE"50V"
TOLERANCE"5%"
MATERIAL"EMPTY"
LOCATION"C1307"
CDS_LIB"pure_quanta"
$SEC"1"
CDS_SEC"1";
"B"
$PN"2"8;
"A"
$PN"1"27;
%"Q_RES"
"1","(-2075,8750)","0","pure_quanta","I40";
;
PART_NUMBER"CS00002JB13"
VALUE"0"
TOLERANCE"5%"
PACK_TYPE"0402LF"
MATERIAL"EMPTY"
LOCATION"PR4698"
CDS_LIB"pure_quanta"
WATTAGE"1/16W"
$SEC"1"
CDS_SEC"1";
"B"
$PN"2"5;
"A"
$PN"1"19;
%"Q_RES"
"1","(-2075,9000)","0","pure_quanta","I41";
;
PART_NUMBER"CS00002JB13"
PACK_TYPE"0402LF"
MATERIAL"CHIP"
TOLERANCE"5%"
VALUE"0"
LOCATION"PR4683"
CDS_LIB"pure_quanta"
WATTAGE"1/16W"
$SEC"1"
CDS_SEC"1";
"B"
$PN"2"6;
"A"
$PN"1"19;
%"Q_CAP"
"1","(-2675,9650)","0","pure_quanta","I42";
;
PART_NUMBER"CH622KMEA03"
TOLERANCE"20%"
MATERIAL"X6S"
PACK_TYPE"C0805"
VOLTAGE"4V"
VALUE"22UF"
LOCATION"PC1278"
CDS_LIB"pure_quanta"
BOM_COST"VR_PCH"
$SEC"1"
CDS_SEC"1";
"B"
$PN"2"16;
"A"
$PN"1"6;
%"Q_CAP"
"1","(-2300,9650)","0","pure_quanta","I43";
;
PART_NUMBER"CH622KMEA03"
VALUE"22UF"
VOLTAGE"4V"
TOLERANCE"20%"
MATERIAL"X6S"
PACK_TYPE"C0805"
LOCATION"PC1279"
CDS_LIB"pure_quanta"
BOM_COST"VR_PCH"
$SEC"1"
CDS_SEC"1";
"B"
$PN"2"16;
"A"
$PN"1"6;
%"UNIVERSAL_GND"
"1","(-1900,9275)","0","logical_power","I45";
;
CDS_LIB"logical_power"
HDL_POWER"GND";
"A"16;
%"VCCAUX15"
"1","(-1525,8850)","0","logical_power","I46";
;
HDL_POWER"PVNN_MAIN_CPU0"
CDS_LIB"logical_power";
"A"5;
%"Q_CAP"
"1","(-1900,9650)","0","pure_quanta","I47";
;
PART_NUMBER"CH622KMEA03"
PACK_TYPE"C0805"
MATERIAL"X6S"
TOLERANCE"20%"
VOLTAGE"4V"
VALUE"22UF"
LOCATION"PC1206"
CDS_LIB"pure_quanta"
BOM_COST"VR_PCH"
$SEC"1"
CDS_SEC"1";
"B"
$PN"2"16;
"A"
$PN"1"6;
%"VCCAUX15"
"1","(-1525,10100)","0","logical_power","I48";
;
HDL_POWER"PVNN_MAIN_CPU0"
CDS_LIB"logical_power";
"A"6;
%"Q_RES"
"1","(-9600,10050)","0","pure_quanta","I5";
;
PART_NUMBER"CS31002FB08"
WATTAGE"1/16W"
MATERIAL"EMPTY"
TOLERANCE"1%"
PACK_TYPE"0402LF"
VALUE"10K"
LOCATION"R2338"
CDS_LIB"pure_quanta"
$SEC"1"
CDS_SEC"1";
"B"
$PN"2"27;
"A"
$PN"1"1;
%"UNIVERSAL_GND"
"1","(-9125,9450)","0","logical_power","I6";
;
CDS_LIB"logical_power"
HDL_POWER"GND";
"A"8;
%"Q_CAP"
"1","(-8225,8725)","0","pure_quanta","I7";
;
PART_NUMBER"CH5104KEB02"
PACK_TYPE"C0402"
TOLERANCE"10%"
VOLTAGE"25V"
VALUE"1UF"
MATERIAL"X6S"
LOCATION"PC2221"
SEC_TYPE"C0402"
CDS_LIB"pure_quanta"
SEC"1";
"B"
$PN"2"7;
"A"
$PN"1"25;
%"UNIVERSAL_GND"
"1","(-8650,8975)","0","logical_power","I8";
;
CDS_LIB"logical_power"
HDL_POWER"GND";
"A"9;
%"Q_RES"
"2","(-8650,9275)","0","pure_quanta","I9";
;
PART_NUMBER"CS36042FB04"
VALUE"60.4K"
PACK_TYPE"0402LF"
TOLERANCE"1%"
WATTAGE"1/16W"
MATERIAL"CHIP"
LOCATION"PR1301"
CDS_LIB"pure_quanta"
$SEC"1"
CDS_SEC"1";
"A"
$PN"1"28;
"B"
$PN"2"9;
END.
